(kicad_pcb
	(version 20260206)
	(generator "pcbnew")
	(generator_version "10.0")
	(general
		(thickness 1.6)
		(legacy_teardrops no)
	)
	(paper "A4")
	(title_block
		(title "Bryce Canyon_IOM_M2_16342-2_OCP.brd")
		(comment 1 "Bryce Canyon / footprints 1058-1065 of 1146")
	)
	(layers
		(0 "F.Cu" signal "TOP")
		(4 "In1.Cu" signal "L2GND")
		(6 "In2.Cu" signal "L3")
		(8 "In3.Cu" signal "L4VCC")
		(10 "In4.Cu" signal "L5VCC")
		(12 "In5.Cu" signal "L6")
		(14 "In6.Cu" signal "L7GND")
		(2 "B.Cu" signal "BOTTOM")
		(9 "F.Adhes" user "F.Adhesive")
		(11 "B.Adhes" user "B.Adhesive")
		(13 "F.Paste" user "Package Geometry/Pastemask Top")
		(15 "B.Paste" user "Package Geometry/Pastemask Bottom")
		(5 "F.SilkS" user "Ref Des/Silkscreen Top")
		(7 "B.SilkS" user "Ref Des/Silkscreen Bottom")
		(1 "F.Mask" user "Board Geometry/Soldermask Top")
		(3 "B.Mask" user "Board Geometry/Soldermask Bottom")
		(17 "Dwgs.User" user "User.Drawings")
		(19 "Cmts.User" user "User.Comments")
		(21 "Eco1.User" user "User.Eco1")
		(23 "Eco2.User" user "User.Eco2")
		(25 "Edge.Cuts" user "Board Geometry/Outline")
		(27 "Margin" user)
		(31 "F.CrtYd" user "Package Geometry/Place Bound Top")
		(29 "B.CrtYd" user "Package Geometry/Place Bound Bottom")
		(35 "F.Fab" user "Ref Des/Assembly Top")
		(33 "B.Fab" user "Ref Des/Assembly Bottom")
	)
	(footprint ""
		(layer "B.Cu")
		(at 54.153054 -144.994122 90)
		(property "Reference" "TP83"
			(at 0 0 90)
			(layer "B.SilkS")
			(hide yes)
			(effects
				(font
					(size 1.27 1.27)
				)
				(justify mirror)
			)
		)
		(property "Value" "TPAD28-2-GP"
			(at 0.0127 -1.6637 90)
			(unlocked yes)
			(layer "B.Fab")
			(hide yes)
			(effects
				(font
					(size 1.016 1.016)
					(thickness 0.1524)
				)
				(justify mirror)
			)
		)
		(property "Device Type" "TPAD28"
			(at 0.0127 -3.1877 90)
			(unlocked yes)
			(layer "B.Fab")
			(hide yes)
			(effects
				(font
					(size 1.016 1.016)
					(thickness 0.1524)
				)
				(justify mirror)
			)
		)
		(duplicate_pad_numbers_are_jumpers no)
		(fp_poly
			(pts
				(arc
					(start 0 0.3556)
					(mid 0 -0.3556)
					(end 0 0.3556)
				)
			)
			(stroke
				(width 0)
				(type default)
			)
			(fill no)
			(layer "B.CrtYd")
		)
		(fp_poly
			(pts
				(arc
					(start 0 0.6096)
					(mid 0 -0.6096)
					(end 0 0.6096)
				)
			)
			(stroke
				(width 0)
				(type default)
			)
			(fill no)
			(layer "B.Fab")
		)
		(pad "1" smd circle
			(at 0 0 270)
			(size 0.7112 0.7112)
			(layers "B.Cu" "B.Mask" "B.Paste")
			(net "JTAG_BMC_TDO")
		)
	)
	(footprint ""
		(layer "B.Cu")
		(at 116.74094 -8.97636)
		(property "Reference" "R524"
			(at 0 0 0)
			(layer "B.SilkS")
			(hide yes)
			(effects
				(font
					(size 1.27 1.27)
				)
				(justify mirror)
			)
		)
		(property "Value" "0R2J-2-GP"
			(at -0.064008 -3.993896 0)
			(unlocked yes)
			(layer "B.Fab")
			(hide yes)
			(effects
				(font
					(size 1.016 1.016)
					(thickness 0.1524)
				)
				(justify mirror)
			)
		)
		(property "Device Type" "R402H16"
			(at -0.064008 -5.517896 0)
			(unlocked yes)
			(layer "B.Fab")
			(hide yes)
			(effects
				(font
					(size 1.016 1.016)
					(thickness 0.1524)
				)
				(justify mirror)
			)
		)
		(duplicate_pad_numbers_are_jumpers no)
		(fp_line
			(start -0.508 -0.9398)
			(end 0.508 -0.9398)
			(stroke
				(width 0.1524)
				(type default)
			)
			(layer "B.SilkS")
		)
		(fp_line
			(start 0.508 -0.9398)
			(end 0.508 0.9398)
			(stroke
				(width 0.1524)
				(type default)
			)
			(layer "B.SilkS")
		)
		(fp_rect
			(start 0.508 0.9398)
			(end -0.508 -0.9398)
			(stroke
				(width 0)
				(type default)
			)
			(fill no)
			(layer "B.CrtYd")
		)
		(fp_rect
			(start 0.508 0.9398)
			(end -0.508 -0.9398)
			(stroke
				(width 0)
				(type default)
			)
			(fill no)
			(layer "B.Fab")
		)
		(pad "1" smd custom
			(at 0 -0.4445 180)
			(size 0.1397 0.1397)
			(layers "B.Cu" "B.Mask" "B.Paste")
			(net "IOM_ADM1278_EN")
			(options
				(clearance outline)
				(anchor circle)
			)
			(primitives
				(gr_poly
					(pts
						(arc
							(start -0.1778 0.2794)
							(mid -0.249642 0.249642)
							(end -0.2794 0.1778)
						)
						(arc
							(start -0.2794 -0.1778)
							(mid -0.249642 -0.249642)
							(end -0.1778 -0.2794)
						)
						(arc
							(start 0.1778 -0.2794)
							(mid 0.249642 -0.249642)
							(end 0.2794 -0.1778)
						)
						(arc
							(start 0.2794 0.1778)
							(mid 0.249642 0.249642)
							(end 0.1778 0.2794)
						)
					)
					(width 0)
					(fill yes)
				)
			)
		)
		(pad "2" smd custom
			(at 0 0.4445 180)
			(size 0.1397 0.1397)
			(layers "B.Cu" "B.Mask" "B.Paste")
			(net "MB0_HS_ENABLE")
			(options
				(clearance outline)
				(anchor circle)
			)
			(primitives
				(gr_poly
					(pts
						(arc
							(start -0.1778 0.2794)
							(mid -0.249642 0.249642)
							(end -0.2794 0.1778)
						)
						(arc
							(start -0.2794 -0.1778)
							(mid -0.249642 -0.249642)
							(end -0.1778 -0.2794)
						)
						(arc
							(start 0.1778 -0.2794)
							(mid 0.249642 -0.249642)
							(end 0.2794 -0.1778)
						)
						(arc
							(start 0.2794 0.1778)
							(mid 0.249642 0.249642)
							(end 0.1778 0.2794)
						)
					)
					(width 0)
					(fill yes)
				)
			)
		)
	)
	(footprint ""
		(layer "B.Cu")
		(at 23.440644 -131.007358 180)
		(property "Reference" "R249"
			(at 0 0 0)
			(layer "B.SilkS")
			(hide yes)
			(effects
				(font
					(size 1.27 1.27)
				)
				(justify mirror)
			)
		)
		(property "Value" "120R2F-GP"
			(at -0.064008 -3.993896 180)
			(unlocked yes)
			(layer "B.Fab")
			(hide yes)
			(effects
				(font
					(size 1.016 1.016)
					(thickness 0.1524)
				)
				(justify mirror)
			)
		)
		(property "Device Type" "R402H16"
			(at -0.064008 -5.517896 180)
			(unlocked yes)
			(layer "B.Fab")
			(hide yes)
			(effects
				(font
					(size 1.016 1.016)
					(thickness 0.1524)
				)
				(justify mirror)
			)
		)
		(duplicate_pad_numbers_are_jumpers no)
		(fp_line
			(start 0.508 -0.9398)
			(end 0.508 0.9398)
			(stroke
				(width 0.1524)
				(type default)
			)
			(layer "B.SilkS")
		)
		(fp_line
			(start -0.508 -0.9398)
			(end 0.508 -0.9398)
			(stroke
				(width 0.1524)
				(type default)
			)
			(layer "B.SilkS")
		)
		(fp_rect
			(start 0.508 0.9398)
			(end -0.508 -0.9398)
			(stroke
				(width 0)
				(type default)
			)
			(fill no)
			(layer "B.CrtYd")
		)
		(fp_rect
			(start 0.508 0.9398)
			(end -0.508 -0.9398)
			(stroke
				(width 0)
				(type default)
			)
			(fill no)
			(layer "B.Fab")
		)
		(pad "1" smd custom
			(at 0 -0.4445)
			(size 0.1397 0.1397)
			(layers "B.Cu" "B.Mask" "B.Paste")
			(net "MEMA_7")
			(options
				(clearance outline)
				(anchor circle)
			)
			(primitives
				(gr_poly
					(pts
						(arc
							(start -0.1778 0.2794)
							(mid -0.249642 0.249642)
							(end -0.2794 0.1778)
						)
						(arc
							(start -0.2794 -0.1778)
							(mid -0.249642 -0.249642)
							(end -0.1778 -0.2794)
						)
						(arc
							(start 0.1778 -0.2794)
							(mid 0.249642 -0.249642)
							(end 0.2794 -0.1778)
						)
						(arc
							(start 0.2794 0.1778)
							(mid 0.249642 0.249642)
							(end 0.1778 0.2794)
						)
					)
					(width 0)
					(fill yes)
				)
			)
		)
		(pad "2" smd custom
			(at 0 0.4445)
			(size 0.1397 0.1397)
			(layers "B.Cu" "B.Mask" "B.Paste")
			(net "P1V2_STBY")
			(options
				(clearance outline)
				(anchor circle)
			)
			(primitives
				(gr_poly
					(pts
						(arc
							(start -0.1778 0.2794)
							(mid -0.249642 0.249642)
							(end -0.2794 0.1778)
						)
						(arc
							(start -0.2794 -0.1778)
							(mid -0.249642 -0.249642)
							(end -0.1778 -0.2794)
						)
						(arc
							(start 0.1778 -0.2794)
							(mid 0.249642 -0.249642)
							(end 0.2794 -0.1778)
						)
						(arc
							(start 0.2794 0.1778)
							(mid 0.249642 0.249642)
							(end 0.1778 0.2794)
						)
					)
					(width 0)
					(fill yes)
				)
			)
		)
	)
	(footprint ""
		(layer "B.Cu")
		(at 64.0842 -147.066 180)
		(property "Reference" "R201"
			(at 0 0 0)
			(layer "B.SilkS")
			(hide yes)
			(effects
				(font
					(size 1.27 1.27)
				)
				(justify mirror)
			)
		)
		(property "Value" "2K2R2F-GP"
			(at -0.064008 -3.993896 180)
			(unlocked yes)
			(layer "B.Fab")
			(hide yes)
			(effects
				(font
					(size 1.016 1.016)
					(thickness 0.1524)
				)
				(justify mirror)
			)
		)
		(property "Device Type" "R402H16"
			(at -0.064008 -5.517896 180)
			(unlocked yes)
			(layer "B.Fab")
			(hide yes)
			(effects
				(font
					(size 1.016 1.016)
					(thickness 0.1524)
				)
				(justify mirror)
			)
		)
		(duplicate_pad_numbers_are_jumpers no)
		(fp_line
			(start 0.508 -0.9398)
			(end 0.508 0.9398)
			(stroke
				(width 0.1524)
				(type default)
			)
			(layer "B.SilkS")
		)
		(fp_line
			(start -0.508 -0.9398)
			(end 0.508 -0.9398)
			(stroke
				(width 0.1524)
				(type default)
			)
			(layer "B.SilkS")
		)
		(fp_rect
			(start 0.508 0.9398)
			(end -0.508 -0.9398)
			(stroke
				(width 0)
				(type default)
			)
			(fill no)
			(layer "B.CrtYd")
		)
		(fp_rect
			(start 0.508 0.9398)
			(end -0.508 -0.9398)
			(stroke
				(width 0)
				(type default)
			)
			(fill no)
			(layer "B.Fab")
		)
		(pad "1" smd custom
			(at 0 -0.4445)
			(size 0.1397 0.1397)
			(layers "B.Cu" "B.Mask" "B.Paste")
			(net "I2C_MEZZ_FRU_SENSOR_SCL")
			(options
				(clearance outline)
				(anchor circle)
			)
			(primitives
				(gr_poly
					(pts
						(arc
							(start -0.1778 0.2794)
							(mid -0.249642 0.249642)
							(end -0.2794 0.1778)
						)
						(arc
							(start -0.2794 -0.1778)
							(mid -0.249642 -0.249642)
							(end -0.1778 -0.2794)
						)
						(arc
							(start 0.1778 -0.2794)
							(mid 0.249642 -0.249642)
							(end 0.2794 -0.1778)
						)
						(arc
							(start 0.2794 0.1778)
							(mid 0.249642 0.249642)
							(end 0.1778 0.2794)
						)
					)
					(width 0)
					(fill yes)
				)
			)
		)
		(pad "2" smd custom
			(at 0 0.4445)
			(size 0.1397 0.1397)
			(layers "B.Cu" "B.Mask" "B.Paste")
			(net "P3V3_STBY")
			(options
				(clearance outline)
				(anchor circle)
			)
			(primitives
				(gr_poly
					(pts
						(arc
							(start -0.1778 0.2794)
							(mid -0.249642 0.249642)
							(end -0.2794 0.1778)
						)
						(arc
							(start -0.2794 -0.1778)
							(mid -0.249642 -0.249642)
							(end -0.1778 -0.2794)
						)
						(arc
							(start 0.1778 -0.2794)
							(mid 0.249642 -0.249642)
							(end 0.2794 -0.1778)
						)
						(arc
							(start 0.2794 0.1778)
							(mid 0.249642 0.249642)
							(end 0.1778 0.2794)
						)
					)
					(width 0)
					(fill yes)
				)
			)
		)
	)
	(footprint ""
		(layer "B.Cu")
		(at 220.101414 -100.682044 180)
		(property "Reference" "C647"
			(at 0 0 0)
			(layer "B.SilkS")
			(hide yes)
			(effects
				(font
					(size 1.27 1.27)
				)
				(justify mirror)
			)
		)
		(property "Value" "SC4D7U25V5KX-1-GP"
			(at 0.0762 -6.1214 180)
			(unlocked yes)
			(layer "B.Fab")
			(hide yes)
			(effects
				(font
					(size 1.016 1.016)
					(thickness 0.1524)
				)
				(justify mirror)
			)
		)
		(property "Device Type" "C805H58"
			(at 0.0762 -8.1534 180)
			(unlocked yes)
			(layer "B.Fab")
			(hide yes)
			(effects
				(font
					(size 1.016 1.016)
					(thickness 0.1524)
				)
				(justify mirror)
			)
		)
		(duplicate_pad_numbers_are_jumpers no)
		(fp_line
			(start -0.635 0)
			(end 0.635 0)
			(stroke
				(width 0.508)
				(type default)
			)
			(layer "B.SilkS")
		)
		(fp_rect
			(start 0.9652 1.778)
			(end -0.9652 -1.778)
			(stroke
				(width 0)
				(type default)
			)
			(fill no)
			(layer "B.CrtYd")
		)
		(fp_poly
			(pts
				(xy 0.9652 -1.778) (xy -0.9652 -1.778) (xy -0.9652 1.778) (xy 0.9652 1.778)
			)
			(stroke
				(width 0)
				(type default)
			)
			(fill no)
			(layer "B.Fab")
		)
		(pad "1" smd rect
			(at 0 -0.9652)
			(size 1.397 1.143)
			(layers "B.Cu" "B.Mask" "B.Paste")
			(net "P12V_STBY_VDD_U81")
		)
		(pad "2" smd rect
			(at 0 0.9652)
			(size 1.397 1.143)
			(layers "B.Cu" "B.Mask" "B.Paste")
			(net "GND")
		)
	)
	(footprint ""
		(layer "B.Cu")
		(at 199.813418 -130.391408 180)
		(property "Reference" "C608"
			(at 0 0 0)
			(layer "B.SilkS")
			(hide yes)
			(effects
				(font
					(size 1.27 1.27)
				)
				(justify mirror)
			)
		)
		(property "Value" "SCD1U16V2KX-3GP"
			(at -1.1811 -2.7051 180)
			(unlocked yes)
			(layer "B.Fab")
			(hide yes)
			(effects
				(font
					(size 1.016 1.016)
					(thickness 0.1524)
				)
				(justify mirror)
			)
		)
		(property "Device Type" "C402H22"
			(at -1.1811 -4.2291 180)
			(unlocked yes)
			(layer "B.Fab")
			(hide yes)
			(effects
				(font
					(size 1.016 1.016)
					(thickness 0.1524)
				)
				(justify mirror)
			)
		)
		(duplicate_pad_numbers_are_jumpers no)
		(fp_rect
			(start 0.4318 0.9525)
			(end -0.4318 -0.9525)
			(stroke
				(width 0)
				(type default)
			)
			(fill no)
			(layer "B.CrtYd")
		)
		(fp_rect
			(start 0.4318 0.9525)
			(end -0.4318 -0.9525)
			(stroke
				(width 0)
				(type default)
			)
			(fill no)
			(layer "B.Fab")
		)
		(pad "1" smd custom
			(at 0 -0.4445)
			(size 0.1524 0.1524)
			(layers "B.Cu" "B.Mask" "B.Paste")
			(net "P3V3_M2")
			(options
				(clearance outline)
				(anchor circle)
			)
			(primitives
				(gr_poly
					(pts
						(arc
							(start 0.3048 0.2032)
							(mid 0.275042 0.275042)
							(end 0.2032 0.3048)
						)
						(arc
							(start -0.2032 0.3048)
							(mid -0.275042 0.275042)
							(end -0.3048 0.2032)
						)
						(arc
							(start -0.3048 -0.2032)
							(mid -0.275042 -0.275042)
							(end -0.2032 -0.3048)
						)
						(arc
							(start 0.2032 -0.3048)
							(mid 0.275042 -0.275042)
							(end 0.3048 -0.2032)
						)
					)
					(width 0)
					(fill yes)
				)
			)
		)
		(pad "2" smd custom
			(at 0 0.4445)
			(size 0.1524 0.1524)
			(layers "B.Cu" "B.Mask" "B.Paste")
			(net "GND")
			(options
				(clearance outline)
				(anchor circle)
			)
			(primitives
				(gr_poly
					(pts
						(arc
							(start 0.3048 0.2032)
							(mid 0.275042 0.275042)
							(end 0.2032 0.3048)
						)
						(arc
							(start -0.2032 0.3048)
							(mid -0.275042 0.275042)
							(end -0.3048 0.2032)
						)
						(arc
							(start -0.3048 -0.2032)
							(mid -0.275042 -0.275042)
							(end -0.2032 -0.3048)
						)
						(arc
							(start 0.2032 -0.3048)
							(mid 0.275042 -0.275042)
							(end 0.3048 -0.2032)
						)
					)
					(width 0)
					(fill yes)
				)
			)
		)
	)
	(footprint ""
		(layer "B.Cu")
		(at 124.9553 -8.580374 -90)
		(property "Reference" "R433"
			(at 0 0 90)
			(layer "B.SilkS")
			(hide yes)
			(effects
				(font
					(size 1.27 1.27)
				)
				(justify mirror)
			)
		)
		(property "Value" "39K2R2F-L-GP"
			(at -0.064008 -3.993896 270)
			(unlocked yes)
			(layer "B.Fab")
			(hide yes)
			(effects
				(font
					(size 1.016 1.016)
					(thickness 0.1524)
				)
				(justify mirror)
			)
		)
		(property "Device Type" "R402H16"
			(at -0.064008 -5.517896 270)
			(unlocked yes)
			(layer "B.Fab")
			(hide yes)
			(effects
				(font
					(size 1.016 1.016)
					(thickness 0.1524)
				)
				(justify mirror)
			)
		)
		(duplicate_pad_numbers_are_jumpers no)
		(fp_line
			(start -0.508 -0.9398)
			(end 0.508 -0.9398)
			(stroke
				(width 0.1524)
				(type default)
			)
			(layer "B.SilkS")
		)
		(fp_line
			(start 0.508 -0.9398)
			(end 0.508 0.9398)
			(stroke
				(width 0.1524)
				(type default)
			)
			(layer "B.SilkS")
		)
		(fp_rect
			(start 0.508 0.9398)
			(end -0.508 -0.9398)
			(stroke
				(width 0)
				(type default)
			)
			(fill no)
			(layer "B.CrtYd")
		)
		(fp_rect
			(start 0.508 0.9398)
			(end -0.508 -0.9398)
			(stroke
				(width 0)
				(type default)
			)
			(fill no)
			(layer "B.Fab")
		)
		(pad "1" smd custom
			(at 0 -0.4445 90)
			(size 0.1397 0.1397)
			(layers "B.Cu" "B.Mask" "B.Paste")
			(net "P12V_STBY")
			(options
				(clearance outline)
				(anchor circle)
			)
			(primitives
				(gr_poly
					(pts
						(arc
							(start -0.1778 0.2794)
							(mid -0.249642 0.249642)
							(end -0.2794 0.1778)
						)
						(arc
							(start -0.2794 -0.1778)
							(mid -0.249642 -0.249642)
							(end -0.1778 -0.2794)
						)
						(arc
							(start 0.1778 -0.2794)
							(mid 0.249642 -0.249642)
							(end 0.2794 -0.1778)
						)
						(arc
							(start 0.2794 0.1778)
							(mid 0.249642 0.249642)
							(end 0.1778 0.2794)
						)
					)
					(width 0)
					(fill yes)
				)
			)
		)
		(pad "2" smd custom
			(at 0 0.4445 90)
			(size 0.1397 0.1397)
			(layers "B.Cu" "B.Mask" "B.Paste")
			(net "P12V_IOM_PGOOD")
			(options
				(clearance outline)
				(anchor circle)
			)
			(primitives
				(gr_poly
					(pts
						(arc
							(start -0.1778 0.2794)
							(mid -0.249642 0.249642)
							(end -0.2794 0.1778)
						)
						(arc
							(start -0.2794 -0.1778)
							(mid -0.249642 -0.249642)
							(end -0.1778 -0.2794)
						)
						(arc
							(start 0.1778 -0.2794)
							(mid 0.249642 -0.249642)
							(end 0.2794 -0.1778)
						)
						(arc
							(start 0.2794 0.1778)
							(mid 0.249642 0.249642)
							(end 0.1778 0.2794)
						)
					)
					(width 0)
					(fill yes)
				)
			)
		)
	)
	(footprint ""
		(layer "B.Cu")
		(at 51.562 -132.08)
		(property "Reference" "C113"
			(at 0 0 0)
			(layer "B.SilkS")
			(hide yes)
			(effects
				(font
					(size 1.27 1.27)
				)
				(justify mirror)
			)
		)
		(property "Value" "SC1U16V3KX-5GP"
			(at 0 -2.8194 0)
			(unlocked yes)
			(layer "B.Fab")
			(hide yes)
			(effects
				(font
					(size 1.016 1.016)
					(thickness 0.1524)
				)
				(justify mirror)
			)
		)
		(property "Device Type" "C603H36"
			(at 0 -4.3434 0)
			(unlocked yes)
			(layer "B.Fab")
			(hide yes)
			(effects
				(font
					(size 1.016 1.016)
					(thickness 0.1524)
				)
				(justify mirror)
			)
		)
		(duplicate_pad_numbers_are_jumpers no)
		(fp_line
			(start -0.508 0)
			(end 0.508 0)
			(stroke
				(width 0.2032)
				(type default)
			)
			(layer "B.SilkS")
		)
		(fp_rect
			(start 0.5842 1.3335)
			(end -0.5842 -1.3335)
			(stroke
				(width 0)
				(type default)
			)
			(fill no)
			(layer "B.CrtYd")
		)
		(fp_rect
			(start 0.5842 1.3335)
			(end -0.5842 -1.3335)
			(stroke
				(width 0)
				(type default)
			)
			(fill no)
			(layer "B.Fab")
		)
		(pad "1" smd custom
			(at 0 -0.762 180)
			(size 0.2159 0.2159)
			(layers "B.Cu" "B.Mask" "B.Paste")
			(net "P1V15_STBY")
			(options
				(clearance outline)
				(anchor circle)
			)
			(primitives
				(gr_poly
					(pts
						(arc
							(start -0.3302 0.4318)
							(mid -0.402042 0.402042)
							(end -0.4318 0.3302)
						)
						(arc
							(start -0.4318 -0.3302)
							(mid -0.402042 -0.402042)
							(end -0.3302 -0.4318)
						)
						(arc
							(start 0.3302 -0.4318)
							(mid 0.402042 -0.402042)
							(end 0.4318 -0.3302)
						)
						(arc
							(start 0.4318 0.3302)
							(mid 0.402042 0.402042)
							(end 0.3302 0.4318)
						)
					)
					(width 0)
					(fill yes)
				)
			)
		)
		(pad "2" smd custom
			(at 0 0.762 180)
			(size 0.2159 0.2159)
			(layers "B.Cu" "B.Mask" "B.Paste")
			(net "GND")
			(options
				(clearance outline)
				(anchor circle)
			)
			(primitives
				(gr_poly
					(pts
						(arc
							(start -0.3302 0.4318)
							(mid -0.402042 0.402042)
							(end -0.4318 0.3302)
						)
						(arc
							(start -0.4318 -0.3302)
							(mid -0.402042 -0.402042)
							(end -0.3302 -0.4318)
						)
						(arc
							(start 0.3302 -0.4318)
							(mid 0.402042 -0.402042)
							(end 0.4318 -0.3302)
						)
						(arc
							(start 0.4318 0.3302)
							(mid 0.402042 0.402042)
							(end 0.3302 0.4318)
						)
					)
					(width 0)
					(fill yes)
				)
			)
		)
	)
)
